# TIMECARD (Time Appliance Project (Time Card)) — schematic netlist excerpt (pin names and nets, part order shuffled) for the footprints in the layout excerpt that follows; sources: Cadence DE-HDL packaged netlist, KiCad conversion of R4006-B0001-02_R01.brd

J13  CONN_USB_14P_GH4_F_RA_TH  2169890002  pkg P_F_USB_2X7_GH4_RA_P035_PIH  page 24
  GND_1  = SG
  VBUS_1  = XP5R0V_FT4232
  CC1  = UNNAMED_524_CONNUSB14PGH4FRATH_
  D1_P  = FT_USB_DP
  D1_N  = FT_USB_DM
  VBUS_2  = XP5R0V_FT4232
  GND_2  = SG
  GND_3  = SG
  VBUS_3  = XP5R0V_FT4232
  CC2  = UNNAMED_524_CONNUSB14PGH4FRAT_1
  D2_P  = FT_USB_DP
  D2_N  = FT_USB_DM
  VBUS_4  = XP5R0V_FT4232
  GND_4  = SG
  GH1  = SG
  GH2  = SG
  GH3  = SG
  GH4  = SG

(kicad_pcb
	(version 20260206)
	(generator "pcbnew")
	(generator_version "10.0")
	(general
		(thickness 1.6)
		(legacy_teardrops no)
	)
	(paper "A4")
	(title_block
		(title "timecard-production-celestica-r4006 — R4006-B0001-02_R01.brd")
		(comment 1 "Time Appliance Project (Time Card) / footprint 208 of 1113 (J13), pads 1-14 of 14")
	)
	(layers
		(0 "F.Cu" signal "TOP")
		(4 "In1.Cu" signal "L02_GND1")
		(6 "In2.Cu" signal "L03_SIG1")
		(8 "In3.Cu" signal "L04_GND2")
		(10 "In4.Cu" signal "L05_VCC1")
		(12 "In5.Cu" signal "L06_VCC2")
		(14 "In6.Cu" signal "L07_GND3")
		(16 "In7.Cu" signal "L08_SIG2")
		(18 "In8.Cu" signal "L09_GND4")
		(2 "B.Cu" signal "BOTTOM")
		(9 "F.Adhes" user "F.Adhesive")
		(11 "B.Adhes" user "B.Adhesive")
		(13 "F.Paste" user "Package Geometry/Pastemask Top")
		(15 "B.Paste" user "Package Geometry/Pastemask Bottom")
		(5 "F.SilkS" user "Ref Des/Silkscreen Top")
		(7 "B.SilkS" user "Ref Des/Silkscreen Bottom")
		(1 "F.Mask" user "Board Geometry/Soldermask Top")
		(3 "B.Mask" user "Board Geometry/Soldermask Bottom")
		(17 "Dwgs.User" user "User.Drawings")
		(19 "Cmts.User" user "User.Comments")
		(21 "Eco1.User" user "User.Eco1")
		(23 "Eco2.User" user "User.Eco2")
		(25 "Edge.Cuts" user "Board Geometry/Outline")
		(27 "Margin" user)
		(31 "F.CrtYd" user "Package Geometry/Place Bound Top")
		(29 "B.CrtYd" user "Package Geometry/Place Bound Bottom")
		(35 "F.Fab" user "Ref Des/Assembly Top")
		(33 "B.Fab" user "Ref Des/Assembly Bottom")
	)
	(footprint ""
		(layer "F.Cu")
		(at 6.249924 -87.1601 -90)
		(property "Reference" "J13"
			(at -3.60553 1.677924 0)
			(unlocked yes)
			(layer "F.SilkS")
			(effects
				(font
					(size 0.7874 0.5842)
					(thickness 0.1524)
				)
			)
		)
		(property "Value" ""
			(at 0 0 270)
			(layer "F.Fab")
			(effects
				(font
					(size 1.27 1.27)
				)
			)
		)
		(property "Device Type" "CONN_USB_14P_GH4_F_RA_TH-G200-A"
			(at 0.389636 9.511792 270)
			(unlocked yes)
			(layer "F.Fab")
			(hide yes)
			(effects
				(font
					(size 0.7874 0.5842)
					(thickness 0.000001)
				)
			)
		)
		(property "User Part Number" "PARTNUM*"
			(at 0.389636 10.705592 270)
			(unlocked yes)
			(layer "Cmts.User")
			(hide yes)
			(effects
				(font
					(size 0.7874 0.5842)
					(thickness 0.000001)
				)
			)
		)
		(duplicate_pad_numbers_are_jumpers no)
		(pad "A1" thru_hole circle
			(at 0 0 270)
			(size 0.6096 0.6096)
			(drill 0.4064)
			(layers "*.Cu" "*.Mask")
			(remove_unused_layers no)
			(net "SG")
			(thermal_gap 0.1905)
			(padstack
				(mode front_inner_back)
				(layer "Inner"
					(shape circle)
					(size 0.6096 0.6096)
					(clearance 0.1905)
				)
				(layer "B.Cu"
					(shape circle)
					(size 0.6096 0.6096)
				)
			)
		)
		(pad "A4" thru_hole circle
			(at 0 -0.900176 270)
			(size 0.6096 0.6096)
			(drill 0.4064)
			(layers "*.Cu" "*.Mask")
			(remove_unused_layers no)
			(net "XP5R0V_FT4232")
			(thermal_gap 0.1905)
			(padstack
				(mode front_inner_back)
				(layer "Inner"
					(shape circle)
					(size 0.6096 0.6096)
					(clearance 0.1905)
				)
				(layer "B.Cu"
					(shape circle)
					(size 0.6096 0.6096)
				)
			)
		)
		(pad "A5" thru_hole circle
			(at 0 -1.800352 270)
			(size 0.6096 0.6096)
			(drill 0.4064)
			(layers "*.Cu" "*.Mask")
			(remove_unused_layers no)
			(net "UNNAMED_524_CONNUSB14PGH4FRATH_")
			(thermal_gap 0.1905)
			(padstack
				(mode front_inner_back)
				(layer "Inner"
					(shape circle)
					(size 0.6096 0.6096)
					(clearance 0.1905)
				)
				(layer "B.Cu"
					(shape circle)
					(size 0.6096 0.6096)
				)
			)
		)
		(pad "A9" thru_hole circle
			(at 0 -4.50088 270)
			(size 0.6096 0.6096)
			(drill 0.4064)
			(layers "*.Cu" "*.Mask")
			(remove_unused_layers no)
			(net "XP5R0V_FT4232")
			(thermal_gap 0.1905)
			(padstack
				(mode front_inner_back)
				(layer "Inner"
					(shape circle)
					(size 0.6096 0.6096)
					(clearance 0.1905)
				)
				(layer "B.Cu"
					(shape circle)
					(size 0.6096 0.6096)
				)
			)
		)
		(pad "A12" thru_hole circle
			(at 0 -5.401056 270)
			(size 0.6096 0.6096)
			(drill 0.4064)
			(layers "*.Cu" "*.Mask")
			(remove_unused_layers no)
			(net "SG")
			(thermal_gap 0.1905)
			(padstack
				(mode front_inner_back)
				(layer "Inner"
					(shape circle)
					(size 0.6096 0.6096)
					(clearance 0.1905)
				)
				(layer "B.Cu"
					(shape circle)
					(size 0.6096 0.6096)
				)
			)
		)
		(pad "B1" thru_hole circle
			(at 0.77978 -4.950968 270)
			(size 0.6096 0.6096)
			(drill 0.4064)
			(layers "*.Cu" "*.Mask")
			(remove_unused_layers no)
			(net "SG")
			(thermal_gap 0.1905)
			(padstack
				(mode front_inner_back)
				(layer "Inner"
					(shape circle)
					(size 0.6096 0.6096)
					(clearance 0.1905)
				)
				(layer "B.Cu"
					(shape circle)
					(size 0.6096 0.6096)
				)
			)
		)
		(pad "B4" thru_hole circle
			(at 0.77978 -4.050792 270)
			(size 0.6096 0.6096)
			(drill 0.4064)
			(layers "*.Cu" "*.Mask")
			(remove_unused_layers no)
			(net "XP5R0V_FT4232")
			(thermal_gap 0.1905)
			(padstack
				(mode front_inner_back)
				(layer "Inner"
					(shape circle)
					(size 0.6096 0.6096)
					(clearance 0.1905)
				)
				(layer "B.Cu"
					(shape circle)
					(size 0.6096 0.6096)
				)
			)
		)
		(pad "B5" thru_hole circle
			(at 0.77978 -3.150616 270)
			(size 0.6096 0.6096)
			(drill 0.4064)
			(layers "*.Cu" "*.Mask")
			(remove_unused_layers no)
			(net "UNNAMED_524_CONNUSB14PGH4FRAT_1")
			(thermal_gap 0.1905)
			(padstack
				(mode front_inner_back)
				(layer "Inner"
					(shape circle)
					(size 0.6096 0.6096)
					(clearance 0.1905)
				)
				(layer "B.Cu"
					(shape circle)
					(size 0.6096 0.6096)
				)
			)
		)
		(pad "B9" thru_hole circle
			(at 0.77978 -0.450088 270)
			(size 0.6096 0.6096)
			(drill 0.4064)
			(layers "*.Cu" "*.Mask")
			(remove_unused_layers no)
			(net "XP5R0V_FT4232")
			(thermal_gap 0.1905)
			(padstack
				(mode front_inner_back)
				(layer "Inner"
					(shape circle)
					(size 0.6096 0.6096)
					(clearance 0.1905)
				)
				(layer "B.Cu"
					(shape circle)
					(size 0.6096 0.6096)
				)
			)
		)
		(pad "B12" thru_hole circle
			(at 0.77978 0.450088 270)
			(size 0.6096 0.6096)
			(drill 0.4064)
			(layers "*.Cu" "*.Mask")
			(remove_unused_layers no)
			(net "SG")
			(thermal_gap 0.1905)
			(padstack
				(mode front_inner_back)
				(layer "Inner"
					(shape circle)
					(size 0.6096 0.6096)
					(clearance 0.1905)
				)
				(layer "B.Cu"
					(shape circle)
					(size 0.6096 0.6096)
				)
			)
		)
		(pad "GH1" thru_hole oval
			(at -2.140204 -4.851146 270)
			(size 0.889 1.905)
			(drill oval 0.6096 1.6002)
			(layers "*.Cu" "*.Mask")
			(remove_unused_layers no)
			(net "SG")
			(thermal_gap 0.1524)
			(padstack
				(mode front_inner_back)
				(layer "Inner"
					(shape oval)
					(size 0.889 1.905)
					(clearance 0.1524)
				)
				(layer "B.Cu"
					(shape oval)
					(size 0.889 1.905)
				)
			)
		)
		(pad "GH2" thru_hole oval
			(at 2.91973 -4.851146 270)
			(size 0.889 1.905)
			(drill oval 0.6096 1.6002)
			(layers "*.Cu" "*.Mask")
			(remove_unused_layers no)
			(net "SG")
			(thermal_gap 0.1524)
			(padstack
				(mode front_inner_back)
				(layer "Inner"
					(shape oval)
					(size 0.889 1.905)
					(clearance 0.1524)
				)
				(layer "B.Cu"
					(shape oval)
					(size 0.889 1.905)
				)
			)
		)
		(pad "GH3" thru_hole oval
			(at -1.04013 -0.051054 270)
			(size 0.889 1.905)
			(drill oval 0.6096 1.6002)
			(layers "*.Cu" "*.Mask")
			(remove_unused_layers no)
			(net "SG")
			(thermal_gap 0.1524)
			(padstack
				(mode front_inner_back)
				(layer "Inner"
					(shape oval)
					(size 0.889 1.905)
					(clearance 0.1524)
				)
				(layer "B.Cu"
					(shape oval)
					(size 0.889 1.905)
				)
			)
		)
		(pad "GH4" thru_hole oval
			(at 1.81991 -0.051054 270)
			(size 0.889 1.905)
			(drill oval 0.6096 1.6002)
			(layers "*.Cu" "*.Mask")
			(remove_unused_layers no)
			(net "SG")
			(thermal_gap 0.1524)
			(padstack
				(mode front_inner_back)
				(layer "Inner"
					(shape oval)
					(size 0.889 1.905)
					(clearance 0.1524)
				)
				(layer "B.Cu"
					(shape oval)
					(size 0.889 1.905)
				)
			)
		)
	)
)
